(kicad_pcb
	(version 20260206)
	(generator "pcbnew")
	(generator_version "10.0")
	(general
		(thickness 1.6)
		(legacy_teardrops no)
	)
	(paper "A4")
	(title_block
		(title "baseboard — 13948-1b.1110WZS1818.brd")
		(comment 1 "Honey Badger (Wiwynn) / footprints 2369-2375 of 2523")
	)
	(layers
		(0 "F.Cu" signal "TOP")
		(4 "In1.Cu" signal "L2GND")
		(6 "In2.Cu" signal "L3")
		(8 "In3.Cu" signal "L4VCC")
		(10 "In4.Cu" signal "L5VCC")
		(12 "In5.Cu" signal "L6")
		(14 "In6.Cu" signal "L7GND")
		(2 "B.Cu" signal "BOTTOM")
		(9 "F.Adhes" user "F.Adhesive")
		(11 "B.Adhes" user "B.Adhesive")
		(13 "F.Paste" user "Package Geometry/Pastemask Top")
		(15 "B.Paste" user "Package Geometry/Pastemask Bottom")
		(5 "F.SilkS" user "Ref Des/Silkscreen Top")
		(7 "B.SilkS" user "Ref Des/Silkscreen Bottom")
		(1 "F.Mask" user "Board Geometry/Soldermask Top")
		(3 "B.Mask" user "Board Geometry/Soldermask Bottom")
		(17 "Dwgs.User" user "User.Drawings")
		(19 "Cmts.User" user "User.Comments")
		(21 "Eco1.User" user "User.Eco1")
		(23 "Eco2.User" user "User.Eco2")
		(25 "Edge.Cuts" user "Board Geometry/Outline")
		(27 "Margin" user)
		(31 "F.CrtYd" user "Package Geometry/Place Bound Top")
		(29 "B.CrtYd" user "Package Geometry/Place Bound Bottom")
		(35 "F.Fab" user "Ref Des/Assembly Top")
		(33 "B.Fab" user "Ref Des/Assembly Bottom")
	)
	(footprint ""
		(layer "B.Cu")
		(at 96.314006 -54.70906 90)
		(property "Reference" "SC981"
			(at 0 0 90)
			(layer "B.SilkS")
			(hide yes)
			(effects
				(font
					(size 1.27 1.27)
				)
				(justify mirror)
			)
		)
		(property "Value" "SCD1U16V2KX-3GP"
			(at -1.1811 -2.7051 90)
			(unlocked yes)
			(layer "B.Fab")
			(hide yes)
			(effects
				(font
					(size 1.016 1.016)
					(thickness 0.1524)
				)
				(justify mirror)
			)
		)
		(property "Device Type" "C402H22"
			(at -1.1811 -4.2291 90)
			(unlocked yes)
			(layer "B.Fab")
			(hide yes)
			(effects
				(font
					(size 1.016 1.016)
					(thickness 0.1524)
				)
				(justify mirror)
			)
		)
		(duplicate_pad_numbers_are_jumpers no)
		(fp_rect
			(start 0.4318 0.9525)
			(end -0.4318 -0.9525)
			(stroke
				(width 0)
				(type default)
			)
			(fill no)
			(layer "B.CrtYd")
		)
		(fp_rect
			(start 0.4318 0.9525)
			(end -0.4318 -0.9525)
			(stroke
				(width 0)
				(type default)
			)
			(fill no)
			(layer "B.Fab")
		)
		(pad "1" smd custom
			(at 0 -0.4445 270)
			(size 0.1524 0.1524)
			(layers "B.Cu" "B.Mask" "B.Paste")
			(net "P1V8_C")
			(options
				(clearance outline)
				(anchor circle)
			)
			(primitives
				(gr_poly
					(pts
						(arc
							(start 0.3048 0.2032)
							(mid 0.275042 0.275042)
							(end 0.2032 0.3048)
						)
						(arc
							(start -0.2032 0.3048)
							(mid -0.275042 0.275042)
							(end -0.3048 0.2032)
						)
						(arc
							(start -0.3048 -0.2032)
							(mid -0.275042 -0.275042)
							(end -0.2032 -0.3048)
						)
						(arc
							(start 0.2032 -0.3048)
							(mid 0.275042 -0.275042)
							(end 0.3048 -0.2032)
						)
					)
					(width 0)
					(fill yes)
				)
			)
		)
		(pad "2" smd custom
			(at 0 0.4445 270)
			(size 0.1524 0.1524)
			(layers "B.Cu" "B.Mask" "B.Paste")
			(net "GND")
			(options
				(clearance outline)
				(anchor circle)
			)
			(primitives
				(gr_poly
					(pts
						(arc
							(start 0.3048 0.2032)
							(mid 0.275042 0.275042)
							(end 0.2032 0.3048)
						)
						(arc
							(start -0.2032 0.3048)
							(mid -0.275042 0.275042)
							(end -0.3048 0.2032)
						)
						(arc
							(start -0.3048 -0.2032)
							(mid -0.275042 -0.275042)
							(end -0.2032 -0.3048)
						)
						(arc
							(start 0.2032 -0.3048)
							(mid 0.275042 -0.275042)
							(end 0.3048 -0.2032)
						)
					)
					(width 0)
					(fill yes)
				)
			)
		)
	)
	(footprint ""
		(layer "B.Cu")
		(at 197.821296 -87.388192 180)
		(property "Reference" "SC1134"
			(at 0 0 0)
			(layer "B.SilkS")
			(hide yes)
			(effects
				(font
					(size 1.27 1.27)
				)
				(justify mirror)
			)
		)
		(property "Value" "SCD1U6D3V1KX-GP"
			(at 2.8321 -1.7399 180)
			(unlocked yes)
			(layer "B.Fab")
			(hide yes)
			(effects
				(font
					(size 1.016 1.016)
					(thickness 0.1524)
				)
				(justify mirror)
			)
		)
		(property "Device Type" "C0201H13"
			(at 2.8321 -3.2639 180)
			(unlocked yes)
			(layer "B.Fab")
			(hide yes)
			(effects
				(font
					(size 1.016 1.016)
					(thickness 0.1524)
				)
				(justify mirror)
			)
		)
		(duplicate_pad_numbers_are_jumpers no)
		(fp_rect
			(start 0.2794 0.6477)
			(end -0.2794 -0.6477)
			(stroke
				(width 0)
				(type default)
			)
			(fill no)
			(layer "B.CrtYd")
		)
		(fp_rect
			(start 0.2794 0.6477)
			(end -0.2794 -0.6477)
			(stroke
				(width 0)
				(type default)
			)
			(fill no)
			(layer "B.Fab")
		)
		(pad "1" smd custom
			(at 0 -0.2794)
			(size 0.0762 0.0762)
			(layers "B.Cu" "B.Mask" "B.Paste")
			(net "GB_VDDH2")
			(options
				(clearance outline)
				(anchor circle)
			)
			(primitives
				(gr_poly
					(pts
						(arc
							(start 0.1524 0.127)
							(mid 0.137521 0.162921)
							(end 0.1016 0.1778)
						)
						(arc
							(start -0.1016 0.1778)
							(mid -0.137521 0.162921)
							(end -0.1524 0.127)
						)
						(arc
							(start -0.1524 -0.127)
							(mid -0.137521 -0.162921)
							(end -0.1016 -0.1778)
						)
						(arc
							(start 0.1016 -0.1778)
							(mid 0.137521 -0.162921)
							(end 0.1524 -0.127)
						)
					)
					(width 0)
					(fill yes)
				)
			)
		)
		(pad "2" smd custom
			(at 0 0.2794)
			(size 0.0762 0.0762)
			(layers "B.Cu" "B.Mask" "B.Paste")
			(net "GND")
			(options
				(clearance outline)
				(anchor circle)
			)
			(primitives
				(gr_poly
					(pts
						(arc
							(start 0.1524 0.127)
							(mid 0.137521 0.162921)
							(end 0.1016 0.1778)
						)
						(arc
							(start -0.1016 0.1778)
							(mid -0.137521 0.162921)
							(end -0.1524 0.127)
						)
						(arc
							(start -0.1524 -0.127)
							(mid -0.137521 -0.162921)
							(end -0.1016 -0.1778)
						)
						(arc
							(start 0.1016 -0.1778)
							(mid 0.137521 -0.162921)
							(end 0.1524 -0.127)
						)
					)
					(width 0)
					(fill yes)
				)
			)
		)
	)
	(footprint ""
		(layer "B.Cu")
		(at 92.583 -34.163 -90)
		(property "Reference" "SC947"
			(at 0 0 90)
			(layer "B.SilkS")
			(hide yes)
			(effects
				(font
					(size 1.27 1.27)
				)
				(justify mirror)
			)
		)
		(property "Value" "SC1U6D3V1MX-GP"
			(at -1.9177 2.0193 270)
			(unlocked yes)
			(layer "B.Fab")
			(hide yes)
			(effects
				(font
					(size 1.016 1.016)
					(thickness 0.1524)
				)
				(justify mirror)
			)
		)
		(property "Device Type" "C0201H14"
			(at -1.9177 0.4953 270)
			(unlocked yes)
			(layer "B.Fab")
			(hide yes)
			(effects
				(font
					(size 1.016 1.016)
					(thickness 0.1524)
				)
				(justify mirror)
			)
		)
		(duplicate_pad_numbers_are_jumpers no)
		(fp_rect
			(start 0.1524 0.3048)
			(end -0.1524 -0.3048)
			(stroke
				(width 0)
				(type default)
			)
			(fill no)
			(layer "B.CrtYd")
		)
		(fp_poly
			(pts
				(xy 0.2794 0.6477) (xy 0.2794 -0.6477) (xy -0.2794 -0.6477) (xy -0.2794 -0.1905) (xy -0.1524 -0.1905)
				(xy -0.1524 -0.3048) (xy 0.1524 -0.3048) (xy 0.1524 0.3048) (xy -0.1524 0.3048) (xy -0.1524 -0.1778)
				(xy -0.2794 -0.1778) (xy -0.2794 0.6477)
			)
			(stroke
				(width 0)
				(type default)
			)
			(fill no)
			(layer "B.CrtYd")
		)
		(fp_rect
			(start 0.2794 0.6477)
			(end -0.2794 -0.6477)
			(stroke
				(width 0)
				(type default)
			)
			(fill no)
			(layer "B.Fab")
		)
		(pad "1" smd custom
			(at 0 -0.2794 90)
			(size 0.0762 0.0762)
			(layers "B.Cu" "B.Mask" "B.Paste")
			(net "PCE_AVDD")
			(options
				(clearance outline)
				(anchor circle)
			)
			(primitives
				(gr_poly
					(pts
						(arc
							(start 0.1524 0.127)
							(mid 0.137521 0.162921)
							(end 0.1016 0.1778)
						)
						(arc
							(start -0.1016 0.1778)
							(mid -0.137521 0.162921)
							(end -0.1524 0.127)
						)
						(arc
							(start -0.1524 -0.127)
							(mid -0.137521 -0.162921)
							(end -0.1016 -0.1778)
						)
						(arc
							(start 0.1016 -0.1778)
							(mid 0.137521 -0.162921)
							(end 0.1524 -0.127)
						)
					)
					(width 0)
					(fill yes)
				)
			)
		)
		(pad "2" smd custom
			(at 0 0.2794 90)
			(size 0.0762 0.0762)
			(layers "B.Cu" "B.Mask" "B.Paste")
			(net "GND")
			(options
				(clearance outline)
				(anchor circle)
			)
			(primitives
				(gr_poly
					(pts
						(arc
							(start 0.1524 0.127)
							(mid 0.137521 0.162921)
							(end 0.1016 0.1778)
						)
						(arc
							(start -0.1016 0.1778)
							(mid -0.137521 0.162921)
							(end -0.1524 0.127)
						)
						(arc
							(start -0.1524 -0.127)
							(mid -0.137521 -0.162921)
							(end -0.1016 -0.1778)
						)
						(arc
							(start 0.1016 -0.1778)
							(mid 0.137521 -0.162921)
							(end 0.1524 -0.127)
						)
					)
					(width 0)
					(fill yes)
				)
			)
		)
	)
	(footprint ""
		(layer "B.Cu")
		(at 120.30837 -88.2142 90)
		(property "Reference" "SC1140"
			(at 0 0 90)
			(layer "B.SilkS")
			(hide yes)
			(effects
				(font
					(size 1.27 1.27)
				)
				(justify mirror)
			)
		)
		(property "Value" "SCD1U6D3V1KX-GP"
			(at 2.8321 -1.7399 90)
			(unlocked yes)
			(layer "B.Fab")
			(hide yes)
			(effects
				(font
					(size 1.016 1.016)
					(thickness 0.1524)
				)
				(justify mirror)
			)
		)
		(property "Device Type" "C0201H13"
			(at 2.8321 -3.2639 90)
			(unlocked yes)
			(layer "B.Fab")
			(hide yes)
			(effects
				(font
					(size 1.016 1.016)
					(thickness 0.1524)
				)
				(justify mirror)
			)
		)
		(duplicate_pad_numbers_are_jumpers no)
		(fp_rect
			(start 0.2794 0.6477)
			(end -0.2794 -0.6477)
			(stroke
				(width 0)
				(type default)
			)
			(fill no)
			(layer "B.CrtYd")
		)
		(fp_rect
			(start 0.2794 0.6477)
			(end -0.2794 -0.6477)
			(stroke
				(width 0)
				(type default)
			)
			(fill no)
			(layer "B.Fab")
		)
		(pad "1" smd custom
			(at 0 -0.2794 270)
			(size 0.0762 0.0762)
			(layers "B.Cu" "B.Mask" "B.Paste")
			(net "GB_VDDH2")
			(options
				(clearance outline)
				(anchor circle)
			)
			(primitives
				(gr_poly
					(pts
						(arc
							(start 0.1524 0.127)
							(mid 0.137521 0.162921)
							(end 0.1016 0.1778)
						)
						(arc
							(start -0.1016 0.1778)
							(mid -0.137521 0.162921)
							(end -0.1524 0.127)
						)
						(arc
							(start -0.1524 -0.127)
							(mid -0.137521 -0.162921)
							(end -0.1016 -0.1778)
						)
						(arc
							(start 0.1016 -0.1778)
							(mid 0.137521 -0.162921)
							(end 0.1524 -0.127)
						)
					)
					(width 0)
					(fill yes)
				)
			)
		)
		(pad "2" smd custom
			(at 0 0.2794 270)
			(size 0.0762 0.0762)
			(layers "B.Cu" "B.Mask" "B.Paste")
			(net "GND")
			(options
				(clearance outline)
				(anchor circle)
			)
			(primitives
				(gr_poly
					(pts
						(arc
							(start 0.1524 0.127)
							(mid 0.137521 0.162921)
							(end 0.1016 0.1778)
						)
						(arc
							(start -0.1016 0.1778)
							(mid -0.137521 0.162921)
							(end -0.1524 0.127)
						)
						(arc
							(start -0.1524 -0.127)
							(mid -0.137521 -0.162921)
							(end -0.1016 -0.1778)
						)
						(arc
							(start 0.1016 -0.1778)
							(mid 0.137521 -0.162921)
							(end 0.1524 -0.127)
						)
					)
					(width 0)
					(fill yes)
				)
			)
		)
	)
	(footprint ""
		(layer "B.Cu")
		(at 287.994852 -174.971456 -90)
		(property "Reference" "R230"
			(at 0 0 90)
			(layer "B.SilkS")
			(hide yes)
			(effects
				(font
					(size 1.27 1.27)
				)
				(justify mirror)
			)
		)
		(property "Value" "100KR2F-L1-GP"
			(at -0.064008 -3.993896 270)
			(unlocked yes)
			(layer "B.Fab")
			(hide yes)
			(effects
				(font
					(size 1.016 1.016)
					(thickness 0.1524)
				)
				(justify mirror)
			)
		)
		(property "Device Type" "R402H16"
			(at -0.064008 -5.517896 270)
			(unlocked yes)
			(layer "B.Fab")
			(hide yes)
			(effects
				(font
					(size 1.016 1.016)
					(thickness 0.1524)
				)
				(justify mirror)
			)
		)
		(duplicate_pad_numbers_are_jumpers no)
		(fp_line
			(start -0.508 -0.9398)
			(end 0.508 -0.9398)
			(stroke
				(width 0.1524)
				(type default)
			)
			(layer "B.SilkS")
		)
		(fp_line
			(start 0.508 -0.9398)
			(end 0.508 0.9398)
			(stroke
				(width 0.1524)
				(type default)
			)
			(layer "B.SilkS")
		)
		(fp_rect
			(start 0.508 0.9398)
			(end -0.508 -0.9398)
			(stroke
				(width 0)
				(type default)
			)
			(fill no)
			(layer "B.CrtYd")
		)
		(fp_rect
			(start 0.508 0.9398)
			(end -0.508 -0.9398)
			(stroke
				(width 0)
				(type default)
			)
			(fill no)
			(layer "B.Fab")
		)
		(pad "1" smd custom
			(at 0 -0.4445 90)
			(size 0.1397 0.1397)
			(layers "B.Cu" "B.Mask" "B.Paste")
			(net "GND")
			(options
				(clearance outline)
				(anchor circle)
			)
			(primitives
				(gr_poly
					(pts
						(arc
							(start -0.1778 0.2794)
							(mid -0.249642 0.249642)
							(end -0.2794 0.1778)
						)
						(arc
							(start -0.2794 -0.1778)
							(mid -0.249642 -0.249642)
							(end -0.1778 -0.2794)
						)
						(arc
							(start 0.1778 -0.2794)
							(mid 0.249642 -0.249642)
							(end 0.2794 -0.1778)
						)
						(arc
							(start 0.2794 0.1778)
							(mid 0.249642 0.249642)
							(end 0.1778 0.2794)
						)
					)
					(width 0)
					(fill yes)
				)
			)
		)
		(pad "2" smd custom
			(at 0 0.4445 90)
			(size 0.1397 0.1397)
			(layers "B.Cu" "B.Mask" "B.Paste")
			(net "PD_PERST_N")
			(options
				(clearance outline)
				(anchor circle)
			)
			(primitives
				(gr_poly
					(pts
						(arc
							(start -0.1778 0.2794)
							(mid -0.249642 0.249642)
							(end -0.2794 0.1778)
						)
						(arc
							(start -0.2794 -0.1778)
							(mid -0.249642 -0.249642)
							(end -0.1778 -0.2794)
						)
						(arc
							(start 0.1778 -0.2794)
							(mid 0.249642 -0.249642)
							(end 0.2794 -0.1778)
						)
						(arc
							(start 0.2794 0.1778)
							(mid 0.249642 0.249642)
							(end 0.1778 0.2794)
						)
					)
					(width 0)
					(fill yes)
				)
			)
		)
	)
	(footprint ""
		(layer "B.Cu")
		(at 68.498212 -244.856)
		(property "Reference" "C297"
			(at 0 0 0)
			(layer "B.SilkS")
			(hide yes)
			(effects
				(font
					(size 1.27 1.27)
				)
				(justify mirror)
			)
		)
		(property "Value" "SCD1U25V2KX-2-GP"
			(at -1.1811 -2.7051 0)
			(unlocked yes)
			(layer "B.Fab")
			(hide yes)
			(effects
				(font
					(size 1.016 1.016)
					(thickness 0.1524)
				)
				(justify mirror)
			)
		)
		(property "Device Type" "C402H22"
			(at -1.1811 -4.2291 0)
			(unlocked yes)
			(layer "B.Fab")
			(hide yes)
			(effects
				(font
					(size 1.016 1.016)
					(thickness 0.1524)
				)
				(justify mirror)
			)
		)
		(duplicate_pad_numbers_are_jumpers no)
		(fp_rect
			(start 0.4318 0.9525)
			(end -0.4318 -0.9525)
			(stroke
				(width 0)
				(type default)
			)
			(fill no)
			(layer "B.CrtYd")
		)
		(fp_rect
			(start 0.4318 0.9525)
			(end -0.4318 -0.9525)
			(stroke
				(width 0)
				(type default)
			)
			(fill no)
			(layer "B.Fab")
		)
		(pad "1" smd custom
			(at 0 -0.4445 180)
			(size 0.1524 0.1524)
			(layers "B.Cu" "B.Mask" "B.Paste")
			(net "P12V_PCIE")
			(options
				(clearance outline)
				(anchor circle)
			)
			(primitives
				(gr_poly
					(pts
						(arc
							(start 0.3048 0.2032)
							(mid 0.275042 0.275042)
							(end 0.2032 0.3048)
						)
						(arc
							(start -0.2032 0.3048)
							(mid -0.275042 0.275042)
							(end -0.3048 0.2032)
						)
						(arc
							(start -0.3048 -0.2032)
							(mid -0.275042 -0.275042)
							(end -0.2032 -0.3048)
						)
						(arc
							(start 0.2032 -0.3048)
							(mid 0.275042 -0.275042)
							(end 0.3048 -0.2032)
						)
					)
					(width 0)
					(fill yes)
				)
			)
		)
		(pad "2" smd custom
			(at 0 0.4445 180)
			(size 0.1524 0.1524)
			(layers "B.Cu" "B.Mask" "B.Paste")
			(net "GND")
			(options
				(clearance outline)
				(anchor circle)
			)
			(primitives
				(gr_poly
					(pts
						(arc
							(start 0.3048 0.2032)
							(mid 0.275042 0.275042)
							(end 0.2032 0.3048)
						)
						(arc
							(start -0.2032 0.3048)
							(mid -0.275042 0.275042)
							(end -0.3048 0.2032)
						)
						(arc
							(start -0.3048 -0.2032)
							(mid -0.275042 -0.275042)
							(end -0.2032 -0.3048)
						)
						(arc
							(start 0.2032 -0.3048)
							(mid 0.275042 -0.275042)
							(end 0.3048 -0.2032)
						)
					)
					(width 0)
					(fill yes)
				)
			)
		)
	)
	(footprint ""
		(layer "B.Cu")
		(at 124.403612 -217.678 -90)
		(property "Reference" "SR1261"
			(at 0 0 90)
			(layer "B.SilkS")
			(hide yes)
			(effects
				(font
					(size 1.27 1.27)
				)
				(justify mirror)
			)
		)
		(property "Value" "0R2J-2-GP"
			(at -0.064008 -3.993896 270)
			(unlocked yes)
			(layer "B.Fab")
			(hide yes)
			(effects
				(font
					(size 1.016 1.016)
					(thickness 0.1524)
				)
				(justify mirror)
			)
		)
		(property "Device Type" "R402H16"
			(at -0.064008 -5.517896 270)
			(unlocked yes)
			(layer "B.Fab")
			(hide yes)
			(effects
				(font
					(size 1.016 1.016)
					(thickness 0.1524)
				)
				(justify mirror)
			)
		)
		(duplicate_pad_numbers_are_jumpers no)
		(fp_line
			(start -0.508 -0.9398)
			(end 0.508 -0.9398)
			(stroke
				(width 0.1524)
				(type default)
			)
			(layer "B.SilkS")
		)
		(fp_line
			(start 0.508 -0.9398)
			(end 0.508 0.9398)
			(stroke
				(width 0.1524)
				(type default)
			)
			(layer "B.SilkS")
		)
		(fp_rect
			(start 0.508 0.9398)
			(end -0.508 -0.9398)
			(stroke
				(width 0)
				(type default)
			)
			(fill no)
			(layer "B.CrtYd")
		)
		(fp_rect
			(start 0.508 0.9398)
			(end -0.508 -0.9398)
			(stroke
				(width 0)
				(type default)
			)
			(fill no)
			(layer "B.Fab")
		)
		(pad "1" smd custom
			(at 0 -0.4445 90)
			(size 0.1397 0.1397)
			(layers "B.Cu" "B.Mask" "B.Paste")
			(net "EXP_SDA_L_0")
			(options
				(clearance outline)
				(anchor circle)
			)
			(primitives
				(gr_poly
					(pts
						(arc
							(start -0.1778 0.2794)
							(mid -0.249642 0.249642)
							(end -0.2794 0.1778)
						)
						(arc
							(start -0.2794 -0.1778)
							(mid -0.249642 -0.249642)
							(end -0.1778 -0.2794)
						)
						(arc
							(start 0.1778 -0.2794)
							(mid 0.249642 -0.249642)
							(end 0.2794 -0.1778)
						)
						(arc
							(start 0.2794 0.1778)
							(mid 0.249642 0.249642)
							(end 0.1778 0.2794)
						)
					)
					(width 0)
					(fill yes)
				)
			)
		)
		(pad "2" smd custom
			(at 0 0.4445 90)
			(size 0.1397 0.1397)
			(layers "B.Cu" "B.Mask" "B.Paste")
			(net "REDV_I2C_SDA")
			(options
				(clearance outline)
				(anchor circle)
			)
			(primitives
				(gr_poly
					(pts
						(arc
							(start -0.1778 0.2794)
							(mid -0.249642 0.249642)
							(end -0.2794 0.1778)
						)
						(arc
							(start -0.2794 -0.1778)
							(mid -0.249642 -0.249642)
							(end -0.1778 -0.2794)
						)
						(arc
							(start 0.1778 -0.2794)
							(mid 0.249642 -0.249642)
							(end 0.2794 -0.1778)
						)
						(arc
							(start 0.2794 0.1778)
							(mid 0.249642 0.249642)
							(end 0.1778 0.2794)
						)
					)
					(width 0)
					(fill yes)
				)
			)
		)
	)
)
